# S9S_MB_2U (Grand Teton) — schematic netlist excerpt (pin names and nets, part order shuffled) for the footprints in the layout excerpt that follows; sources: Cadence DE-HDL packaged netlist, KiCad conversion of 03242023_DA0F0TMBIJ0_F0T_Motherboard_J_brd_V01_OCP.brd

R2415  Q_RES  0 5% CHIP  pkg 0402LF  page 240 : A = SMB_1_BMC_GPU_SCL ; B = SMB_PCIE3_3V3AUX_SCL_R
R1216  Q_RES  1.5K 1% CHIP  pkg 0402LF  page 80 : A = P3V3_AUX ; B = FM_S3M_CPU0_CPLD_CRC_ERROR
PC302_P0_2  Q_CAP  22UF 16V 20% X6S  pkg C0805  page 267 : A = SW_P12V_PVCCIN_CPU0_FLT ; B = GND

(kicad_pcb
	(version 20260206)
	(generator "pcbnew")
	(generator_version "10.0")
	(general
		(thickness 1.6)
		(legacy_teardrops no)
	)
	(paper "A4")
	(title_block
		(title "03242023_DA0F0TMBIJ0_F0T_Motherboard_J_brd_V01_OCP.brd")
		(comment 1 "Grand Teton / footprints 4511-4513 of 6105")
	)
	(layers
		(0 "F.Cu" signal "TOP")
		(4 "In1.Cu" signal "GND")
		(6 "In2.Cu" signal "IN1")
		(8 "In3.Cu" signal "GND1")
		(10 "In4.Cu" signal "IN2")
		(12 "In5.Cu" signal "GND2")
		(14 "In6.Cu" signal "IN3")
		(16 "In7.Cu" signal "GND3")
		(18 "In8.Cu" signal "VCC")
		(20 "In9.Cu" signal "VCC1")
		(22 "In10.Cu" signal "GND4")
		(24 "In11.Cu" signal "IN4")
		(26 "In12.Cu" signal "GND5")
		(28 "In13.Cu" signal "IN5")
		(30 "In14.Cu" signal "GND6")
		(32 "In15.Cu" signal "IN6")
		(34 "In16.Cu" signal "GND7")
		(2 "B.Cu" signal "BOTTOM")
		(9 "F.Adhes" user "F.Adhesive")
		(11 "B.Adhes" user "B.Adhesive")
		(13 "F.Paste" user "Package Geometry/Pastemask Top")
		(15 "B.Paste" user "Package Geometry/Pastemask Bottom")
		(5 "F.SilkS" user "Ref Des/Silkscreen Top")
		(7 "B.SilkS" user "Ref Des/Silkscreen Bottom")
		(1 "F.Mask" user "Board Geometry/Soldermask Top")
		(3 "B.Mask" user "Board Geometry/Soldermask Bottom")
		(17 "Dwgs.User" user "User.Drawings")
		(19 "Cmts.User" user "User.Comments")
		(21 "Eco1.User" user "User.Eco1")
		(23 "Eco2.User" user "User.Eco2")
		(25 "Edge.Cuts" user "Board Geometry/Outline")
		(27 "Margin" user)
		(31 "F.CrtYd" user "Package Geometry/Place Bound Top")
		(29 "B.CrtYd" user "Package Geometry/Place Bound Bottom")
		(35 "F.Fab" user "Ref Des/Assembly Top")
		(33 "B.Fab" user "Ref Des/Assembly Bottom")
	)
	(footprint ""
		(layer "B.Cu")
		(at 154.00782 -13.762228 90)
		(property "Reference" "R2415"
			(at 0 0 90)
			(layer "B.SilkS")
			(hide yes)
			(effects
				(font
					(size 1.27 1.27)
				)
				(justify mirror)
			)
		)
		(property "Value" ""
			(at 0 0 90)
			(layer "B.Fab")
			(effects
				(font
					(size 1.27 1.27)
				)
				(justify mirror)
			)
		)
		(duplicate_pad_numbers_are_jumpers no)
		(fp_line
			(start 0.7874 -0.4064)
			(end -0.7874 -0.4064)
			(stroke
				(width 0.1524)
				(type default)
			)
			(layer "B.SilkS")
		)
		(fp_line
			(start -0.7874 -0.4064)
			(end -0.7874 0.4064)
			(stroke
				(width 0.1524)
				(type default)
			)
			(layer "B.SilkS")
		)
		(fp_line
			(start 0.7874 0.4064)
			(end 0.7874 -0.4064)
			(stroke
				(width 0.1524)
				(type default)
			)
			(layer "B.SilkS")
		)
		(fp_line
			(start -0.7874 0.4064)
			(end 0.7874 0.4064)
			(stroke
				(width 0.1524)
				(type default)
			)
			(layer "B.SilkS")
		)
		(fp_line
			(start 0.67945 -0.305054)
			(end 0.12065 -0.305054)
			(stroke
				(width 0.1)
				(type default)
			)
			(layer "B.Fab")
		)
		(fp_line
			(start 0.12065 -0.305054)
			(end 0.12065 -0.2794)
			(stroke
				(width 0.1)
				(type default)
			)
			(layer "B.Fab")
		)
		(fp_line
			(start -0.12065 -0.3048)
			(end -0.67945 -0.3048)
			(stroke
				(width 0.1)
				(type default)
			)
			(layer "B.Fab")
		)
		(fp_line
			(start -0.67945 -0.3048)
			(end -0.67945 0.3048)
			(stroke
				(width 0.1)
				(type default)
			)
			(layer "B.Fab")
		)
		(fp_line
			(start 0.12065 -0.2794)
			(end -0.12065 -0.2794)
			(stroke
				(width 0.1)
				(type default)
			)
			(layer "B.Fab")
		)
		(fp_line
			(start -0.12065 -0.2794)
			(end -0.12065 -0.3048)
			(stroke
				(width 0.1)
				(type default)
			)
			(layer "B.Fab")
		)
		(fp_line
			(start 0.12065 0.2794)
			(end 0.12065 0.3048)
			(stroke
				(width 0.1)
				(type default)
			)
			(layer "B.Fab")
		)
		(fp_line
			(start -0.120396 0.2794)
			(end 0.12065 0.2794)
			(stroke
				(width 0.1)
				(type default)
			)
			(layer "B.Fab")
		)
		(fp_line
			(start 0.67945 0.3048)
			(end 0.67945 -0.305054)
			(stroke
				(width 0.1)
				(type default)
			)
			(layer "B.Fab")
		)
		(fp_line
			(start 0.12065 0.3048)
			(end 0.67945 0.3048)
			(stroke
				(width 0.1)
				(type default)
			)
			(layer "B.Fab")
		)
		(fp_line
			(start -0.120396 0.3048)
			(end -0.120396 0.2794)
			(stroke
				(width 0.1)
				(type default)
			)
			(layer "B.Fab")
		)
		(fp_line
			(start -0.67945 0.3048)
			(end -0.120396 0.3048)
			(stroke
				(width 0.1)
				(type default)
			)
			(layer "B.Fab")
		)
		(pad "1" smd circle
			(at 0.40005 0 270)
			(size 0 0)
			(layers "B.Cu" "B.Mask" "B.Paste")
			(net "SMB_1_BMC_GPU_SCL")
		)
		(pad "2" smd circle
			(at -0.40005 0 270)
			(size 0 0)
			(layers "B.Cu" "B.Mask" "B.Paste")
			(net "SMB_PCIE3_3V3AUX_SCL_R")
		)
	)
	(footprint ""
		(layer "B.Cu")
		(at 382.009904 -188.29401)
		(property "Reference" "R1216"
			(at 0 0 0)
			(layer "B.SilkS")
			(hide yes)
			(effects
				(font
					(size 1.27 1.27)
				)
				(justify mirror)
			)
		)
		(property "Value" ""
			(at 0 0 0)
			(layer "B.Fab")
			(effects
				(font
					(size 1.27 1.27)
				)
				(justify mirror)
			)
		)
		(duplicate_pad_numbers_are_jumpers no)
		(fp_line
			(start -0.7874 -0.4064)
			(end -0.7874 0.4064)
			(stroke
				(width 0.1524)
				(type default)
			)
			(layer "B.SilkS")
		)
		(fp_line
			(start -0.7874 0.4064)
			(end 0.7874 0.4064)
			(stroke
				(width 0.1524)
				(type default)
			)
			(layer "B.SilkS")
		)
		(fp_line
			(start 0.7874 -0.4064)
			(end -0.7874 -0.4064)
			(stroke
				(width 0.1524)
				(type default)
			)
			(layer "B.SilkS")
		)
		(fp_line
			(start 0.7874 0.4064)
			(end 0.7874 -0.4064)
			(stroke
				(width 0.1524)
				(type default)
			)
			(layer "B.SilkS")
		)
		(fp_line
			(start -0.67945 -0.3048)
			(end -0.67945 0.3048)
			(stroke
				(width 0.1)
				(type default)
			)
			(layer "B.Fab")
		)
		(fp_line
			(start -0.67945 0.3048)
			(end -0.120396 0.3048)
			(stroke
				(width 0.1)
				(type default)
			)
			(layer "B.Fab")
		)
		(fp_line
			(start -0.12065 -0.3048)
			(end -0.67945 -0.3048)
			(stroke
				(width 0.1)
				(type default)
			)
			(layer "B.Fab")
		)
		(fp_line
			(start -0.12065 -0.2794)
			(end -0.12065 -0.3048)
			(stroke
				(width 0.1)
				(type default)
			)
			(layer "B.Fab")
		)
		(fp_line
			(start -0.120396 0.2794)
			(end 0.12065 0.2794)
			(stroke
				(width 0.1)
				(type default)
			)
			(layer "B.Fab")
		)
		(fp_line
			(start -0.120396 0.3048)
			(end -0.120396 0.2794)
			(stroke
				(width 0.1)
				(type default)
			)
			(layer "B.Fab")
		)
		(fp_line
			(start 0.12065 -0.305054)
			(end 0.12065 -0.2794)
			(stroke
				(width 0.1)
				(type default)
			)
			(layer "B.Fab")
		)
		(fp_line
			(start 0.12065 -0.2794)
			(end -0.12065 -0.2794)
			(stroke
				(width 0.1)
				(type default)
			)
			(layer "B.Fab")
		)
		(fp_line
			(start 0.12065 0.2794)
			(end 0.12065 0.3048)
			(stroke
				(width 0.1)
				(type default)
			)
			(layer "B.Fab")
		)
		(fp_line
			(start 0.12065 0.3048)
			(end 0.67945 0.3048)
			(stroke
				(width 0.1)
				(type default)
			)
			(layer "B.Fab")
		)
		(fp_line
			(start 0.67945 -0.305054)
			(end 0.12065 -0.305054)
			(stroke
				(width 0.1)
				(type default)
			)
			(layer "B.Fab")
		)
		(fp_line
			(start 0.67945 0.3048)
			(end 0.67945 -0.305054)
			(stroke
				(width 0.1)
				(type default)
			)
			(layer "B.Fab")
		)
		(pad "1" smd circle
			(at 0.40005 0 180)
			(size 0 0)
			(layers "B.Cu" "B.Mask" "B.Paste")
			(net "P3V3_AUX")
		)
		(pad "2" smd circle
			(at -0.40005 0 180)
			(size 0 0)
			(layers "B.Cu" "B.Mask" "B.Paste")
			(net "FM_S3M_CPU0_CPLD_CRC_ERROR")
		)
	)
	(footprint ""
		(layer "B.Cu")
		(at 354.601526 -337.564984 -90)
		(property "Reference" "PC302_P0_2"
			(at 0 0 90)
			(layer "B.SilkS")
			(hide yes)
			(effects
				(font
					(size 1.27 1.27)
				)
				(justify mirror)
			)
		)
		(property "Value" ""
			(at 0 0 90)
			(layer "B.Fab")
			(effects
				(font
					(size 1.27 1.27)
				)
				(justify mirror)
			)
		)
		(duplicate_pad_numbers_are_jumpers no)
		(fp_line
			(start -1.524 0.762)
			(end 1.524 0.762)
			(stroke
				(width 0.1524)
				(type default)
			)
			(layer "B.SilkS")
		)
		(fp_line
			(start 1.524 0.762)
			(end 1.524 -0.762)
			(stroke
				(width 0.1524)
				(type default)
			)
			(layer "B.SilkS")
		)
		(fp_line
			(start -1.524 -0.762)
			(end -1.524 0.762)
			(stroke
				(width 0.1524)
				(type default)
			)
			(layer "B.SilkS")
		)
		(fp_line
			(start 1.524 -0.762)
			(end -1.524 -0.762)
			(stroke
				(width 0.1524)
				(type default)
			)
			(layer "B.SilkS")
		)
		(fp_line
			(start -1.1049 0.724916)
			(end -1.1049 -0.724916)
			(stroke
				(width 0.1)
				(type default)
			)
			(layer "B.Fab")
		)
		(fp_line
			(start 1.1049 0.724916)
			(end -1.1049 0.724916)
			(stroke
				(width 0.1)
				(type default)
			)
			(layer "B.Fab")
		)
		(fp_line
			(start -1.1049 -0.724916)
			(end 1.1049 -0.724916)
			(stroke
				(width 0.1)
				(type default)
			)
			(layer "B.Fab")
		)
		(fp_line
			(start 1.1049 -0.724916)
			(end 1.1049 0.724916)
			(stroke
				(width 0.1)
				(type default)
			)
			(layer "B.Fab")
		)
		(pad "1" smd rect
			(at 0.889 0 270)
			(size 1.016 1.27)
			(layers "B.Cu" "B.Mask" "B.Paste")
			(net "SW_P12V_PVCCIN_CPU0_FLT")
		)
		(pad "2" smd rect
			(at -0.889 0 270)
			(size 1.016 1.27)
			(layers "B.Cu" "B.Mask" "B.Paste")
			(net "GND")
		)
	)
)
